# Thunderbolt PCIe Adaper — KiCad project settings (.kicad_pro: net classes, design rules, text variables)
{
  "board": {
    "3dviewports": [],
    "design_settings": {
      "defaults": {
        "board_outline_line_width": 0.09999999999999999,
        "copper_line_width": 0.19999999999999998,
        "copper_text_italic": false,
        "copper_text_size_h": 1.5,
        "copper_text_size_v": 1.5,
        "copper_text_thickness": 0.3,
        "copper_text_upright": false,
        "courtyard_line_width": 0.049999999999999996,
        "dimension_precision": 4,
        "dimension_units": 3,
        "dimensions": {
          "arrow_length": 1270000,
          "extension_offset": 500000,
          "keep_text_aligned": true,
          "suppress_zeroes": false,
          "text_position": 0,
          "units_format": 1
        },
        "fab_line_width": 0.09999999999999999,
        "fab_text_italic": false,
        "fab_text_size_h": 1.0,
        "fab_text_size_v": 1.0,
        "fab_text_thickness": 0.15,
        "fab_text_upright": false,
        "other_line_width": 0.15,
        "other_text_italic": false,
        "other_text_size_h": 1.0,
        "other_text_size_v": 1.0,
        "other_text_thickness": 0.15,
        "other_text_upright": false,
        "pads": {
          "drill": 0.762,
          "height": 1.524,
          "width": 1.524
        },
        "silk_line_width": 0.15,
        "silk_text_italic": false,
        "silk_text_size_h": 1.0,
        "silk_text_size_v": 1.0,
        "silk_text_thickness": 0.15,
        "silk_text_upright": false,
        "zones": {
          "45_degree_only": false,
          "min_clearance": 0.25
        }
      },
      "diff_pair_dimensions": [
        {
          "gap": 0.0,
          "via_gap": 0.0,
          "width": 0.0
        }
      ],
      "drc_exclusions": [],
      "meta": {
        "version": 2
      },
      "rule_severities": {
        "annular_width": "error",
        "clearance": "error",
        "connection_width": "warning",
        "copper_edge_clearance": "error",
        "copper_sliver": "warning",
        "courtyards_overlap": "error",
        "diff_pair_gap_out_of_range": "error",
        "diff_pair_uncoupled_length_too_long": "error",
        "drill_out_of_range": "error",
        "duplicate_footprints": "warning",
        "extra_footprint": "warning",
        "footprint": "error",
        "footprint_type_mismatch": "error",
        "hole_clearance": "error",
        "hole_near_hole": "error",
        "invalid_outline": "error",
        "isolated_copper": "warning",
        "item_on_disabled_layer": "error",
        "items_not_allowed": "error",
        "length_out_of_range": "error",
        "lib_footprint_issues": "warning",
        "lib_footprint_mismatch": "warning",
        "malformed_courtyard": "error",
        "microvia_drill_out_of_range": "error",
        "missing_courtyard": "warning",
        "missing_footprint": "warning",
        "net_conflict": "warning",
        "npth_inside_courtyard": "warning",
        "padstack": "error",
        "pth_inside_courtyard": "warning",
        "shorting_items": "error",
        "silk_edge_clearance": "warning",
        "silk_over_copper": "warning",
        "silk_overlap": "warning",
        "skew_out_of_range": "error",
        "solder_mask_bridge": "error",
        "starved_thermal": "error",
        "text_height": "warning",
        "text_thickness": "warning",
        "through_hole_pad_without_hole": "error",
        "too_many_vias": "error",
        "track_dangling": "warning",
        "track_width": "error",
        "tracks_crossing": "error",
        "unconnected_items": "error",
        "unresolved_variable": "error",
        "via_dangling": "warning",
        "zones_intersect": "error"
      },
      "rules": {
        "allow_blind_buried_vias": false,
        "allow_microvias": false,
        "max_error": 0.005,
        "min_clearance": 0.09999999999999999,
        "min_connection": 0.0,
        "min_copper_edge_clearance": 0.0,
        "min_hole_clearance": 0.25,
        "min_hole_to_hole": 0.25,
        "min_microvia_diameter": 0.3,
        "min_microvia_drill": 0.09999999999999999,
        "min_resolved_spokes": 2,
        "min_silk_clearance": 0.0,
        "min_text_height": 0.7,
        "min_text_thickness": 0.08,
        "min_through_hole_diameter": 0.09999999999999999,
        "min_track_width": 0.09999999999999999,
        "min_via_annular_width": 0.125,
        "min_via_diameter": 0.44999999999999996,
        "solder_mask_clearance": 0.0,
        "solder_mask_min_width": 0.0,
        "solder_mask_to_copper_clearance": 0.0,
        "use_height_for_length_calcs": true
      },
      "teardrop_options": [
        {
          "td_allow_use_two_tracks": true,
          "td_curve_segcount": 5,
          "td_on_pad_in_zone": false,
          "td_onpadsmd": true,
          "td_onroundshapesonly": false,
          "td_ontrackend": false,
          "td_onviapad": true
        }
      ],
      "teardrop_parameters": [
        {
          "td_curve_segcount": 0,
          "td_height_ratio": 1.0,
          "td_length_ratio": 0.5,
          "td_maxheight": 2.0,
          "td_maxlen": 1.0,
          "td_target_name": "td_round_shape",
          "td_width_to_size_filter_ratio": 0.9
        },
        {
          "td_curve_segcount": 0,
          "td_height_ratio": 1.0,
          "td_length_ratio": 0.5,
          "td_maxheight": 2.0,
          "td_maxlen": 1.0,
          "td_target_name": "td_rect_shape",
          "td_width_to_size_filter_ratio": 0.9
        },
        {
          "td_curve_segcount": 0,
          "td_height_ratio": 1.0,
          "td_length_ratio": 0.5,
          "td_maxheight": 2.0,
          "td_maxlen": 1.0,
          "td_target_name": "td_track_end",
          "td_width_to_size_filter_ratio": 0.9
        }
      ],
      "track_widths": [
        0.0,
        0.1,
        0.25,
        0.4,
        0.6
      ],
      "via_dimensions": [
        {
          "diameter": 0.0,
          "drill": 0.0
        }
      ],
      "zones_allow_external_fillets": false,
      "zones_use_no_outline": true
    },
    "layer_presets": [
      {
        "activeLayer": -2,
        "layers": [
          5,
          6,
          7,
          8,
          9,
          10,
          11,
          12,
          13,
          14,
          15,
          16,
          17,
          18,
          19,
          20,
          21,
          22,
          23,
          24,
          25,
          26,
          27,
          28,
          29,
          30,
          44
        ],
        "name": "Edge.Cuts only",
        "renderLayers": [
          125,
          126,
          127,
          128,
          129,
          130,
          133,
          134,
          135,
          136,
          137,
          138,
          139,
          140,
          141,
          142,
          143,
          144,
          145,
          146,
          147,
          148,
          149,
          150,
          151,
          152,
          153,
          154,
          155,
          157,
          158,
          159,
          160,
          161
        ]
      }
    ],
    "viewports": []
  },
  "boards": [],
  "cvpcb": {
    "equivalence_files": []
  },
  "erc": {
    "erc_exclusions": [],
    "meta": {
      "version": 0
    },
    "pin_map": [
      [
        0,
        0,
        0,
        0,
        0,
        0,
        1,
        0,
        0,
        0,
        0,
        2
      ],
      [
        0,
        2,
        0,
        1,
        0,
        0,
        1,
        0,
        2,
        2,
        2,
        2
      ],
      [
        0,
        0,
        0,
        0,
        0,
        0,
        1,
        0,
        1,
        0,
        1,
        2
      ],
      [
        0,
        1,
        0,
        0,
        0,
        0,
        1,
        1,
        2,
        1,
        1,
        2
      ],
      [
        0,
        0,
        0,
        0,
        0,
        0,
        1,
        0,
        0,
        0,
        0,
        2
      ],
      [
        0,
        0,
        0,
        0,
        0,
        0,
        0,
        0,
        0,
        0,
        0,
        2
      ],
      [
        1,
        1,
        1,
        1,
        1,
        0,
        1,
        1,
        1,
        1,
        1,
        2
      ],
      [
        0,
        0,
        0,
        1,
        0,
        0,
        1,
        0,
        0,
        0,
        0,
        2
      ],
      [
        0,
        2,
        1,
        2,
        0,
        0,
        1,
        0,
        2,
        2,
        2,
        2
      ],
      [
        0,
        2,
        0,
        1,
        0,
        0,
        1,
        0,
        2,
        0,
        0,
        2
      ],
      [
        0,
        2,
        1,
        1,
        0,
        0,
        1,
        0,
        2,
        0,
        0,
        2
      ],
      [
        2,
        2,
        2,
        2,
        2,
        2,
        2,
        2,
        2,
        2,
        2,
        2
      ]
    ],
    "rule_severities": {
      "bus_definition_conflict": "error",
      "bus_entry_needed": "error",
      "bus_to_bus_conflict": "error",
      "bus_to_net_conflict": "error",
      "conflicting_netclasses": "error",
      "different_unit_footprint": "error",
      "different_unit_net": "error",
      "duplicate_reference": "error",
      "duplicate_sheet_names": "error",
      "endpoint_off_grid": "warning",
      "extra_units": "error",
      "global_label_dangling": "warning",
      "hier_label_mismatch": "error",
      "label_dangling": "error",
      "lib_symbol_issues": "warning",
      "missing_bidi_pin": "warning",
      "missing_input_pin": "warning",
      "missing_power_pin": "error",
      "missing_unit": "warning",
      "multiple_net_names": "warning",
      "net_not_bus_member": "warning",
      "no_connect_connected": "warning",
      "no_connect_dangling": "warning",
      "pin_not_connected": "error",
      "pin_not_driven": "error",
      "pin_to_pin": "warning",
      "power_pin_not_driven": "error",
      "similar_labels": "warning",
      "simulation_model_issue": "ignore",
      "unannotated": "error",
      "unit_value_mismatch": "error",
      "unresolved_variable": "error",
      "wire_dangling": "error"
    }
  },
  "libraries": {
    "pinned_footprint_libs": [],
    "pinned_symbol_libs": []
  },
  "meta": {
    "filename": "thunderbolt-pcie-adapter.kicad_pro",
    "version": 1
  },
  "net_settings": {
    "classes": [
      {
        "bus_width": 12,
        "clearance": 0.1,
        "diff_pair_gap": 0.1,
        "diff_pair_via_gap": 0.25,
        "diff_pair_width": 0.1,
        "line_style": 0,
        "microvia_diameter": 0.3,
        "microvia_drill": 0.1,
        "name": "Default",
        "pcb_color": "rgba(0, 0, 0, 0.000)",
        "schematic_color": "rgba(0, 0, 0, 0.000)",
        "track_width": 0.1,
        "via_diameter": 0.45,
        "via_drill": 0.1,
        "wire_width": 6
      },
      {
        "bus_width": 12,
        "clearance": 0.1,
        "diff_pair_gap": 0.2,
        "diff_pair_via_gap": 0.25,
        "diff_pair_width": 0.2,
        "line_style": 0,
        "microvia_diameter": 0.3,
        "microvia_drill": 0.1,
        "name": "85Ohm-diff_PCIE3",
        "pcb_color": "rgba(0, 0, 0, 0.000)",
        "schematic_color": "rgba(0, 0, 0, 0.000)",
        "track_width": 0.1,
        "via_diameter": 0.45,
        "via_drill": 0.1,
        "wire_width": 6
      },
      {
        "bus_width": 12,
        "clearance": 0.1,
        "diff_pair_gap": 0.2,
        "diff_pair_via_gap": 0.25,
        "diff_pair_width": 0.2,
        "line_style": 0,
        "microvia_diameter": 0.3,
        "microvia_drill": 0.1,
        "name": "85Ohm-diff_USB4",
        "pcb_color": "rgba(0, 0, 0, 0.000)",
        "schematic_color": "rgba(0, 0, 0, 0.000)",
        "track_width": 0.1,
        "via_diameter": 0.45,
        "via_drill": 0.1,
        "wire_width": 6
      },
      {
        "bus_width": 12,
        "clearance": 0.1,
        "diff_pair_gap": 0.2,
        "diff_pair_via_gap": 0.25,
        "diff_pair_width": 0.2,
        "line_style": 0,
        "microvia_diameter": 0.3,
        "microvia_drill": 0.1,
        "name": "90Ohm-diff_USB2",
        "pcb_color": "rgba(0, 0, 0, 0.000)",
        "schematic_color": "rgba(0, 0, 0, 0.000)",
        "track_width": 0.1,
        "via_diameter": 0.45,
        "via_drill": 0.1,
        "wire_width": 6
      }
    ],
    "meta": {
      "version": 3
    },
    "net_colors": null,
    "netclass_assignments": null,
    "netclass_patterns": [
      {
        "netclass": "85Ohm-diff_PCIE3",
        "pattern": "/TB Controller/PCIE_CLK_JHL_N"
      },
      {
        "netclass": "85Ohm-diff_PCIE3",
        "pattern": "/TB Controller/PCIE_CLK_JHL_P"
      },
      {
        "netclass": "85Ohm-diff_PCIE3",
        "pattern": "/TB Controller/TX0_N"
      },
      {
        "netclass": "85Ohm-diff_PCIE3",
        "pattern": "/TB Controller/TX0_P"
      },
      {
        "netclass": "85Ohm-diff_PCIE3",
        "pattern": "/TB Controller/TX1_N"
      },
      {
        "netclass": "85Ohm-diff_PCIE3",
        "pattern": "/TB Controller/TX1_P"
      },
      {
        "netclass": "85Ohm-diff_PCIE3",
        "pattern": "/TB Controller/TX2_N"
      },
      {
        "netclass": "85Ohm-diff_PCIE3",
        "pattern": "/TB Controller/TX2_P"
      },
      {
        "netclass": "85Ohm-diff_PCIE3",
        "pattern": "/TB Controller/TX3_N"
      },
      {
        "netclass": "85Ohm-diff_PCIE3",
        "pattern": "/TB Controller/TX3_P"
      },
      {
        "netclass": "85Ohm-diff_PCIE3",
        "pattern": "PCIE_CLK_CON_N"
      },
      {
        "netclass": "85Ohm-diff_PCIE3",
        "pattern": "PCIE_CLK_CON_P"
      },
      {
        "netclass": "85Ohm-diff_PCIE3",
        "pattern": "PCIE_RX0_N"
      },
      {
        "netclass": "85Ohm-diff_PCIE3",
        "pattern": "PCIE_RX0_P"
      },
      {
        "netclass": "85Ohm-diff_PCIE3",
        "pattern": "PCIE_RX1_N"
      },
      {
        "netclass": "85Ohm-diff_PCIE3",
        "pattern": "PCIE_RX1_P"
      },
      {
        "netclass": "85Ohm-diff_PCIE3",
        "pattern": "PCIE_RX2_N"
      },
      {
        "netclass": "85Ohm-diff_PCIE3",
        "pattern": "PCIE_RX2_P"
      },
      {
        "netclass": "85Ohm-diff_PCIE3",
        "pattern": "PCIE_RX3_N"
      },
      {
        "netclass": "85Ohm-diff_PCIE3",
        "pattern": "PCIE_RX3_P"
      },
      {
        "netclass": "85Ohm-diff_PCIE3",
        "pattern": "PCIE_TX0_N"
      },
      {
        "netclass": "85Ohm-diff_PCIE3",
        "pattern": "PCIE_TX0_P"
      },
      {
        "netclass": "85Ohm-diff_PCIE3",
        "pattern": "PCIE_TX1_N"
      },
      {
        "netclass": "85Ohm-diff_PCIE3",
        "pattern": "PCIE_TX1_P"
      },
      {
        "netclass": "85Ohm-diff_PCIE3",
        "pattern": "PCIE_TX2_N"
      },
      {
        "netclass": "85Ohm-diff_PCIE3",
        "pattern": "PCIE_TX2_P"
      },
      {
        "netclass": "85Ohm-diff_PCIE3",
        "pattern": "PCIE_TX3_N"
      },
      {
        "netclass": "85Ohm-diff_PCIE3",
        "pattern": "PCIE_TX3_P"
      },
      {
        "netclass": "85Ohm-diff_USB4",
        "pattern": "/TB Controller/PA_TX0_N"
      },
      {
        "netclass": "85Ohm-diff_USB4",
        "pattern": "/TB Controller/PA_TX0_P"
      },
      {
        "netclass": "85Ohm-diff_USB4",
        "pattern": "/TB Controller/PA_TX1_N"
      },
      {
        "netclass": "85Ohm-diff_USB4",
        "pattern": "/TB Controller/PA_TX1_P"
      },
      {
        "netclass": "85Ohm-diff_USB4",
        "pattern": "TB_RX0_N"
      },
      {
        "netclass": "85Ohm-diff_USB4",
        "pattern": "TB_RX0_P"
      },
      {
        "netclass": "85Ohm-diff_USB4",
        "pattern": "TB_RX1_N"
      },
      {
        "netclass": "85Ohm-diff_USB4",
        "pattern": "TB_RX1_P"
      },
      {
        "netclass": "85Ohm-diff_USB4",
        "pattern": "TB_TX0_N"
      },
      {
        "netclass": "85Ohm-diff_USB4",
        "pattern": "TB_TX0_P"
      },
      {
        "netclass": "85Ohm-diff_USB4",
        "pattern": "TB_TX1_N"
      },
      {
        "netclass": "85Ohm-diff_USB4",
        "pattern": "TB_TX1_P"
      },
      {
        "netclass": "90Ohm-diff_USB2",
        "pattern": "/TB Controller/PA_AUX_N"
      },
      {
        "netclass": "90Ohm-diff_USB2",
        "pattern": "/TB Controller/PA_AUX_P"
      },
      {
        "netclass": "90Ohm-diff_USB2",
        "pattern": "AUX_N"
      },
      {
        "netclass": "90Ohm-diff_USB2",
        "pattern": "AUX_P"
      },
      {
        "netclass": "90Ohm-diff_USB2",
        "pattern": "USB_B_N"
      },
      {
        "netclass": "90Ohm-diff_USB2",
        "pattern": "USB_B_P"
      },
      {
        "netclass": "90Ohm-diff_USB2",
        "pattern": "USB_RP_N"
      },
      {
        "netclass": "90Ohm-diff_USB2",
        "pattern": "USB_RP_P"
      },
      {
        "netclass": "90Ohm-diff_USB2",
        "pattern": "USB_T_N"
      },
      {
        "netclass": "90Ohm-diff_USB2",
        "pattern": "USB_T_P"
      }
    ]
  },
  "pcbnew": {
    "last_paths": {
      "gencad": "",
      "idf": "",
      "netlist": "",
      "specctra_dsn": "",
      "step": "",
      "vrml": "thunderbolt-pcie-adapter.wrl"
    },
    "page_layout_descr_file": ""
  },
  "schematic": {
    "annotate_start_num": 0,
    "drawing": {
      "dashed_lines_dash_length_ratio": 12.0,
      "dashed_lines_gap_length_ratio": 3.0,
      "default_line_thickness": 6.0,
      "default_text_size": 50.0,
      "field_names": [],
      "intersheets_ref_own_page": false,
      "intersheets_ref_prefix": "",
      "intersheets_ref_short": false,
      "intersheets_ref_show": false,
      "intersheets_ref_suffix": "",
      "junction_size_choice": 3,
      "label_size_ratio": 0.375,
      "pin_symbol_size": 25.0,
      "text_offset_ratio": 0.15
    },
    "legacy_lib_dir": "",
    "legacy_lib_list": [],
    "meta": {
      "version": 1
    },
    "net_format_name": "",
    "ngspice": {
      "fix_include_paths": true,
      "fix_passive_vals": false,
      "meta": {
        "version": 0
      },
      "model_mode": 0,
      "workbook_filename": ""
    },
    "page_layout_descr_file": "",
    "plot_directory": "",
    "spice_adjust_passive_values": false,
    "spice_current_sheet_as_root": false,
    "spice_external_command": "spice \"%I\"",
    "spice_model_current_sheet_as_root": true,
    "spice_save_all_currents": false,
    "spice_save_all_voltages": false,
    "subpart_first_id": 65,
    "subpart_id_separator": 0
  },
  "sheets": [
    [
      "",
      ""
    ],
    [
      "",
      "Connectors"
    ],
    [
      "",
      "Power"
    ],
    [
      "",
      "Thunderbolt Controller - Power"
    ],
    [
      "",
      "TB Controller"
    ]
  ],
  "text_variables": {}
}
